# BASEBOARD_FAB2 (Tioga Pass) — schematic netlist excerpt (pin names and nets, part order shuffled) for the footprints in the layout excerpt that follows; sources: Cadence DE-HDL packaged netlist, KiCad conversion of Wiwynn_Tioga_Pass_MB.brd

C6R3  CAPP  470UF 2.5V 20% ALUM  pkg 3018  page 203 : A = PVCCIN_CPU0 ; B = GND
C9M8  CAP_A  0.1UF 16V 10% X7R  pkg 0402V  page 163 : A = PVCCIO_CPU1 ; B = GND
C25W47  CAP  4.7UF 6.3V 10% X6S  pkg 0603  page 149 : A = VCC_D_3V3 ; B = GND

(kicad_pcb
	(version 20260206)
	(generator "pcbnew")
	(generator_version "10.0")
	(general
		(thickness 1.6)
		(legacy_teardrops no)
	)
	(paper "A4")
	(title_block
		(title "Wiwynn_Tioga_Pass_MB.brd")
		(comment 1 "Tioga Pass / footprints 3432-3434 of 4770")
	)
	(layers
		(0 "F.Cu" signal "TOP")
		(4 "In1.Cu" signal "L2GND")
		(6 "In2.Cu" signal "L3")
		(8 "In3.Cu" signal "L4GND")
		(10 "In4.Cu" signal "L5")
		(12 "In5.Cu" signal "L6GND")
		(14 "In6.Cu" signal "L7VCC")
		(16 "In7.Cu" signal "L8VCC")
		(18 "In8.Cu" signal "L9GND")
		(20 "In9.Cu" signal "L10")
		(22 "In10.Cu" signal "L11GND")
		(24 "In11.Cu" signal "L12")
		(26 "In12.Cu" signal "L13GND")
		(2 "B.Cu" signal "BOTTOM")
		(9 "F.Adhes" user "F.Adhesive")
		(11 "B.Adhes" user "B.Adhesive")
		(13 "F.Paste" user "Package Geometry/Pastemask Top")
		(15 "B.Paste" user "Package Geometry/Pastemask Bottom")
		(5 "F.SilkS" user "Ref Des/Silkscreen Top")
		(7 "B.SilkS" user "Ref Des/Silkscreen Bottom")
		(1 "F.Mask" user "Board Geometry/Soldermask Top")
		(3 "B.Mask" user "Board Geometry/Soldermask Bottom")
		(17 "Dwgs.User" user "User.Drawings")
		(19 "Cmts.User" user "User.Comments")
		(21 "Eco1.User" user "User.Eco1")
		(23 "Eco2.User" user "User.Eco2")
		(25 "Edge.Cuts" user "Board Geometry/Outline")
		(27 "Margin" user)
		(31 "F.CrtYd" user "Package Geometry/Place Bound Top")
		(29 "B.CrtYd" user "Package Geometry/Place Bound Bottom")
		(35 "F.Fab" user "Ref Des/Assembly Top")
		(33 "B.Fab" user "Ref Des/Assembly Bottom")
	)
	(footprint ""
		(layer "B.Cu")
		(at 415.442146 -39.735252 90)
		(property "Reference" "C25W47"
			(at -0.97536 0.76708 180)
			(unlocked yes)
			(layer "B.SilkS")
			(effects
				(font
					(size 0.4064 0.254)
					(thickness 0.1524)
				)
				(justify mirror)
			)
		)
		(property "Value" ""
			(at 0 0 90)
			(layer "B.Fab")
			(effects
				(font
					(size 1.27 1.27)
				)
				(justify mirror)
			)
		)
		(duplicate_pad_numbers_are_jumpers no)
		(fp_poly
			(pts
				(xy 0.4953 -0.2032) (xy -0.4953 -0.2032) (xy -0.4953 1.6002) (xy 0.4953 1.6002)
			)
			(stroke
				(width 0)
				(type default)
			)
			(fill no)
			(layer "B.CrtYd")
		)
		(fp_line
			(start 0.4953 -0.2032)
			(end -0.4953 -0.2032)
			(stroke
				(width 0.1)
				(type default)
			)
			(layer "B.Fab")
		)
		(fp_line
			(start -0.4953 -0.2032)
			(end -0.4953 1.6002)
			(stroke
				(width 0.1)
				(type default)
			)
			(layer "B.Fab")
		)
		(fp_line
			(start 0.4953 1.6002)
			(end 0.4953 -0.2032)
			(stroke
				(width 0.1)
				(type default)
			)
			(layer "B.Fab")
		)
		(fp_line
			(start -0.4953 1.6002)
			(end 0.4953 1.6002)
			(stroke
				(width 0.1)
				(type default)
			)
			(layer "B.Fab")
		)
		(pad "1" smd rect
			(at 0 0 270)
			(size 0.762 0.889)
			(layers "B.Cu" "B.Mask" "B.Paste")
			(net "VCC_D_3V3")
		)
		(pad "2" smd rect
			(at 0 1.397 270)
			(size 0.762 0.889)
			(layers "B.Cu" "B.Mask" "B.Paste")
			(net "GND")
		)
		(zone
			(layer "B.Cu")
			(hatch none 0.5)
			(connect_pads
				(clearance 0)
			)
			(min_thickness 0.25)
			(keepout
				(tracks not_allowed)
				(vias allowed)
				(pads allowed)
				(copperpour not_allowed)
				(footprints allowed)
			)
			(placement
				(enabled no)
				(sheetname "")
			)
			(fill
				(thermal_gap 0.5)
				(thermal_bridge_width 0.5)
				(island_removal_mode 0)
			)
			(polygon
				(pts
					(xy 415.886646 -40.116252) (xy 415.886646 -39.354252) (xy 416.394646 -39.354252) (xy 416.394646 -40.116252)
				)
			)
		)
	)
	(footprint ""
		(layer "B.Cu")
		(at 210.847432 -62.611 -90)
		(property "Reference" "C6R3"
			(at -2.64033 -3.528568 0)
			(unlocked yes)
			(layer "B.SilkS")
			(effects
				(font
					(size 0.7874 0.5842)
					(thickness 0.1524)
				)
				(justify mirror)
			)
		)
		(property "Value" ""
			(at 0 0 90)
			(layer "B.Fab")
			(effects
				(font
					(size 1.27 1.27)
				)
				(justify mirror)
			)
		)
		(duplicate_pad_numbers_are_jumpers no)
		(fp_line
			(start -2.286 7.366)
			(end -1.600708 7.366)
			(stroke
				(width 0.1524)
				(type default)
			)
			(layer "B.SilkS")
		)
		(fp_line
			(start -2.286 7.366)
			(end -2.286 1.63195)
			(stroke
				(width 0.1524)
				(type default)
			)
			(layer "B.SilkS")
		)
		(fp_line
			(start 2.286 7.366)
			(end 1.60147 7.366)
			(stroke
				(width 0.1524)
				(type default)
			)
			(layer "B.SilkS")
		)
		(fp_line
			(start 2.286 7.366)
			(end 2.286 1.632712)
			(stroke
				(width 0.1524)
				(type default)
			)
			(layer "B.SilkS")
		)
		(fp_line
			(start -2.504948 1.633728)
			(end -1.6002 1.633728)
			(stroke
				(width 0.1524)
				(type default)
			)
			(layer "B.SilkS")
		)
		(fp_line
			(start 2.563114 1.633728)
			(end 1.6002 1.633728)
			(stroke
				(width 0.1524)
				(type default)
			)
			(layer "B.SilkS")
		)
		(fp_line
			(start -2.504948 -1.616456)
			(end -2.504948 1.633728)
			(stroke
				(width 0.1524)
				(type default)
			)
			(layer "B.SilkS")
		)
		(fp_line
			(start -1.6002 -1.616456)
			(end -2.504948 -1.616456)
			(stroke
				(width 0.1524)
				(type default)
			)
			(layer "B.SilkS")
		)
		(fp_line
			(start 1.6002 -1.616456)
			(end 2.563114 -1.616456)
			(stroke
				(width 0.1524)
				(type default)
			)
			(layer "B.SilkS")
		)
		(fp_line
			(start 2.563114 -1.616456)
			(end 2.563114 1.633728)
			(stroke
				(width 0.1524)
				(type default)
			)
			(layer "B.SilkS")
		)
		(fp_rect
			(start 2.286 7.366)
			(end -2.286 -0.254)
			(stroke
				(width 0)
				(type default)
			)
			(fill no)
			(layer "B.CrtYd")
		)
		(fp_line
			(start -2.286 7.366)
			(end 2.286 7.366)
			(stroke
				(width 0.1)
				(type default)
			)
			(layer "B.Fab")
		)
		(fp_line
			(start 2.286 7.366)
			(end 2.286 -0.254)
			(stroke
				(width 0.1)
				(type default)
			)
			(layer "B.Fab")
		)
		(fp_line
			(start -2.286 -0.254)
			(end -2.286 7.366)
			(stroke
				(width 0.1)
				(type default)
			)
			(layer "B.Fab")
		)
		(fp_line
			(start 2.286 -0.254)
			(end -2.286 -0.254)
			(stroke
				(width 0.1)
				(type default)
			)
			(layer "B.Fab")
		)
		(pad "1" smd rect
			(at 0 0 90)
			(size 2.54 3.048)
			(layers "B.Cu" "B.Mask" "B.Paste")
			(net "PVCCIN_CPU0")
		)
		(pad "2" smd rect
			(at 0 7.112 90)
			(size 2.54 3.048)
			(layers "B.Cu" "B.Mask" "B.Paste")
			(net "GND")
		)
	)
	(footprint ""
		(layer "B.Cu")
		(at -3.09626 -118.78056 180)
		(property "Reference" "C9M8"
			(at 0 0 0)
			(layer "B.SilkS")
			(hide yes)
			(effects
				(font
					(size 1.27 1.27)
				)
				(justify mirror)
			)
		)
		(property "Value" ""
			(at 0 0 0)
			(layer "B.Fab")
			(effects
				(font
					(size 1.27 1.27)
				)
				(justify mirror)
			)
		)
		(duplicate_pad_numbers_are_jumpers no)
		(fp_rect
			(start 0.3048 -0.1016)
			(end -0.3048 0.9906)
			(stroke
				(width 0)
				(type default)
			)
			(fill no)
			(layer "B.CrtYd")
		)
		(fp_line
			(start 0.3048 0.9906)
			(end -0.3048 0.9906)
			(stroke
				(width 0.1)
				(type default)
			)
			(layer "B.Fab")
		)
		(fp_line
			(start 0.3048 -0.1016)
			(end 0.3048 0.9906)
			(stroke
				(width 0.1)
				(type default)
			)
			(layer "B.Fab")
		)
		(fp_line
			(start -0.3048 0.9906)
			(end -0.3048 -0.1016)
			(stroke
				(width 0.1)
				(type default)
			)
			(layer "B.Fab")
		)
		(fp_line
			(start -0.3048 -0.1016)
			(end 0.3048 -0.1016)
			(stroke
				(width 0.1)
				(type default)
			)
			(layer "B.Fab")
		)
		(pad "1" smd rect
			(at 0 0)
			(size 0.508 0.508)
			(layers "B.Cu" "B.Mask" "B.Paste")
			(net "PVCCIO_CPU1")
		)
		(pad "2" smd rect
			(at 0 0.889)
			(size 0.508 0.508)
			(layers "B.Cu" "B.Mask" "B.Paste")
			(net "GND")
		)
		(zone
			(layer "B.Cu")
			(hatch none 0.5)
			(connect_pads
				(clearance 0)
			)
			(min_thickness 0.25)
			(keepout
				(tracks allowed)
				(vias not_allowed)
				(pads allowed)
				(copperpour not_allowed)
				(footprints allowed)
			)
			(placement
				(enabled no)
				(sheetname "")
			)
			(fill
				(thermal_gap 0.5)
				(thermal_bridge_width 0.5)
				(island_removal_mode 0)
			)
			(polygon
				(pts
					(xy -3.35026 -119.03456) (xy -2.84226 -119.03456) (xy -2.84226 -119.41556) (xy -3.35026 -119.41556)
				)
			)
		)
		(zone
			(layer "B.Cu")
			(hatch none 0.5)
			(connect_pads
				(clearance 0)
			)
			(min_thickness 0.25)
			(keepout
				(tracks not_allowed)
				(vias allowed)
				(pads allowed)
				(copperpour not_allowed)
				(footprints allowed)
			)
			(placement
				(enabled no)
				(sheetname "")
			)
			(fill
				(thermal_gap 0.5)
				(thermal_bridge_width 0.5)
				(island_removal_mode 0)
			)
			(polygon
				(pts
					(xy -3.35026 -119.03456) (xy -2.84226 -119.03456) (xy -2.84226 -119.41556) (xy -3.35026 -119.41556)
				)
			)
		)
	)
)
